# T6G (Grand Teton) — schematic netlist excerpt (pin names and nets, part order shuffled) for the footprints in the layout excerpt that follows; sources: Cadence DE-HDL packaged netlist, KiCad conversion of 04192023_DAF0TMB3IC0_F0TG_MB_C_brd_V02_OCP.brd

R6283  Q_RES  1K 1% EMPTY  pkg 0402LF  page 179 : A = P3V3_AUX ; B = USB_HUB2_TI_FULLPWRMGMTZ_MRP_PROG_FUNC3

U124  SN74LVC1G07DBVR  IC  pkg SMLF  page 167
  NC  = NC
  A  = FM_JTAG_BMC_R_OE
  GND  = GND
  Y  = JTAG_BMC_OE
  VCC  = U124_VCC

(kicad_pcb
	(version 20260206)
	(generator "pcbnew")
	(generator_version "10.0")
	(general
		(thickness 1.6)
		(legacy_teardrops no)
	)
	(paper "A4")
	(title_block
		(title "04192023_DAF0TMB3IC0_F0TG_MB_C_brd_V02_OCP.brd")
		(comment 1 "Grand Teton / footprints 4318-4319 of 8354")
	)
	(layers
		(0 "F.Cu" signal "TOP")
		(4 "In1.Cu" signal "GND")
		(6 "In2.Cu" signal "IN1")
		(8 "In3.Cu" signal "GND1")
		(10 "In4.Cu" signal "IN2")
		(12 "In5.Cu" signal "GND2")
		(14 "In6.Cu" signal "IN3")
		(16 "In7.Cu" signal "GND3")
		(18 "In8.Cu" signal "VCC")
		(20 "In9.Cu" signal "VCC1")
		(22 "In10.Cu" signal "GND4")
		(24 "In11.Cu" signal "IN4")
		(26 "In12.Cu" signal "GND5")
		(28 "In13.Cu" signal "IN5")
		(30 "In14.Cu" signal "GND6")
		(32 "In15.Cu" signal "IN6")
		(34 "In16.Cu" signal "GND7")
		(2 "B.Cu" signal "BOTTOM")
		(9 "F.Adhes" user "F.Adhesive")
		(11 "B.Adhes" user "B.Adhesive")
		(13 "F.Paste" user "Package Geometry/Pastemask Top")
		(15 "B.Paste" user "Package Geometry/Pastemask Bottom")
		(5 "F.SilkS" user "Ref Des/Silkscreen Top")
		(7 "B.SilkS" user "Ref Des/Silkscreen Bottom")
		(1 "F.Mask" user "Board Geometry/Soldermask Top")
		(3 "B.Mask" user "Board Geometry/Soldermask Bottom")
		(17 "Dwgs.User" user "User.Drawings")
		(19 "Cmts.User" user "User.Comments")
		(21 "Eco1.User" user "User.Eco1")
		(23 "Eco2.User" user "User.Eco2")
		(25 "Edge.Cuts" user "Board Geometry/Outline")
		(27 "Margin" user)
		(31 "F.CrtYd" user "Package Geometry/Place Bound Top")
		(29 "B.CrtYd" user "Package Geometry/Place Bound Bottom")
		(35 "F.Fab" user "Ref Des/Assembly Top")
		(33 "B.Fab" user "Ref Des/Assembly Bottom")
	)
	(footprint ""
		(layer "F.Cu")
		(at 425.05249 -57.047638)
		(property "Reference" "U124"
			(at -2.032 -2.377948 0)
			(unlocked yes)
			(layer "F.SilkS")
			(effects
				(font
					(size 0.7874 0.5842)
					(thickness 0.1524)
				)
				(justify left)
			)
		)
		(property "Value" ""
			(at 0 0 0)
			(layer "F.Fab")
			(effects
				(font
					(size 1.27 1.27)
				)
			)
		)
		(duplicate_pad_numbers_are_jumpers no)
		(fp_line
			(start -2.0574 -1.651)
			(end -0.381 -1.651)
			(stroke
				(width 0.1524)
				(type default)
			)
			(layer "F.SilkS")
		)
		(fp_line
			(start -2.0574 1.651)
			(end -2.0574 -1.651)
			(stroke
				(width 0.1524)
				(type default)
			)
			(layer "F.SilkS")
		)
		(fp_line
			(start -0.381 -1.651)
			(end 0 -1.016)
			(stroke
				(width 0.1524)
				(type default)
			)
			(layer "F.SilkS")
		)
		(fp_line
			(start 0 -1.016)
			(end 0.381 -1.651)
			(stroke
				(width 0.1524)
				(type default)
			)
			(layer "F.SilkS")
		)
		(fp_line
			(start 0.381 -1.651)
			(end 2.0574 -1.651)
			(stroke
				(width 0.1524)
				(type default)
			)
			(layer "F.SilkS")
		)
		(fp_line
			(start 2.0574 -1.651)
			(end 2.0574 1.651)
			(stroke
				(width 0.1524)
				(type default)
			)
			(layer "F.SilkS")
		)
		(fp_line
			(start 2.0574 1.651)
			(end -2.0574 1.651)
			(stroke
				(width 0.1524)
				(type default)
			)
			(layer "F.SilkS")
		)
		(fp_poly
			(pts
				(xy -2.511806 -1.813052) (xy -3.113278 -1.994662) (xy -2.671318 -2.436622)
			)
			(stroke
				(width 0)
				(type default)
			)
			(fill yes)
			(layer "F.SilkS")
		)
		(fp_line
			(start -1.599946 -1.199896)
			(end -0.899922 -1.199896)
			(stroke
				(width 0.1)
				(type default)
			)
			(layer "F.Fab")
		)
		(fp_line
			(start -1.599946 1.199896)
			(end -1.599946 -1.199896)
			(stroke
				(width 0.1)
				(type default)
			)
			(layer "F.Fab")
		)
		(fp_line
			(start -0.899922 -1.549908)
			(end 0.899922 -1.549908)
			(stroke
				(width 0.1)
				(type default)
			)
			(layer "F.Fab")
		)
		(fp_line
			(start -0.899922 -1.199896)
			(end -0.899922 -1.549908)
			(stroke
				(width 0.1)
				(type default)
			)
			(layer "F.Fab")
		)
		(fp_line
			(start -0.899922 1.199896)
			(end -1.599946 1.199896)
			(stroke
				(width 0.1)
				(type default)
			)
			(layer "F.Fab")
		)
		(fp_line
			(start -0.899922 1.549908)
			(end -0.899922 1.199896)
			(stroke
				(width 0.1)
				(type default)
			)
			(layer "F.Fab")
		)
		(fp_line
			(start 0.899922 -1.549908)
			(end 0.899922 -1.199896)
			(stroke
				(width 0.1)
				(type default)
			)
			(layer "F.Fab")
		)
		(fp_line
			(start 0.899922 -1.199896)
			(end 1.599946 -1.199896)
			(stroke
				(width 0.1)
				(type default)
			)
			(layer "F.Fab")
		)
		(fp_line
			(start 0.899922 1.199896)
			(end 0.899922 1.549908)
			(stroke
				(width 0.1)
				(type default)
			)
			(layer "F.Fab")
		)
		(fp_line
			(start 0.899922 1.549908)
			(end -0.899922 1.549908)
			(stroke
				(width 0.1)
				(type default)
			)
			(layer "F.Fab")
		)
		(fp_line
			(start 1.599946 -1.199896)
			(end 1.599946 1.199896)
			(stroke
				(width 0.1)
				(type default)
			)
			(layer "F.Fab")
		)
		(fp_line
			(start 1.599946 1.199896)
			(end 0.899922 1.199896)
			(stroke
				(width 0.1)
				(type default)
			)
			(layer "F.Fab")
		)
		(fp_poly
			(pts
				(xy -2.71272 -0.719328) (xy -2.71272 -1.344168) (xy -2.159 -1.016)
			)
			(stroke
				(width 0)
				(type default)
			)
			(fill yes)
			(layer "F.Fab")
		)
		(pad "1" smd rect
			(at -1.225042 -0.94996 270)
			(size 0.5588 1.3462)
			(layers "F.Cu" "F.Mask" "F.Paste")
			(net "Net_10728")
		)
		(pad "2" smd rect
			(at -1.225042 0 270)
			(size 0.5588 1.3462)
			(layers "F.Cu" "F.Mask" "F.Paste")
			(net "FM_JTAG_BMC_R_OE")
		)
		(pad "3" smd rect
			(at -1.225042 0.94996 270)
			(size 0.5588 1.3462)
			(layers "F.Cu" "F.Mask" "F.Paste")
			(net "GND")
		)
		(pad "4" smd rect
			(at 1.225042 0.94996 270)
			(size 0.5588 1.3462)
			(layers "F.Cu" "F.Mask" "F.Paste")
			(net "JTAG_BMC_OE")
		)
		(pad "5" smd rect
			(at 1.225042 -0.94996 270)
			(size 0.5588 1.3462)
			(layers "F.Cu" "F.Mask" "F.Paste")
			(net "U124_VCC")
		)
	)
	(footprint ""
		(layer "F.Cu")
		(at 115.315238 -41.17975 -90)
		(property "Reference" "R6283"
			(at 0 0 270)
			(layer "F.SilkS")
			(hide yes)
			(effects
				(font
					(size 1.27 1.27)
				)
			)
		)
		(property "Value" ""
			(at 0 0 270)
			(layer "F.Fab")
			(effects
				(font
					(size 1.27 1.27)
				)
			)
		)
		(duplicate_pad_numbers_are_jumpers no)
		(fp_line
			(start -0.7874 0.4064)
			(end -0.7874 -0.4064)
			(stroke
				(width 0.1524)
				(type default)
			)
			(layer "F.SilkS")
		)
		(fp_line
			(start 0.7874 0.4064)
			(end -0.7874 0.4064)
			(stroke
				(width 0.1524)
				(type default)
			)
			(layer "F.SilkS")
		)
		(fp_line
			(start -0.7874 -0.4064)
			(end 0.7874 -0.4064)
			(stroke
				(width 0.1524)
				(type default)
			)
			(layer "F.SilkS")
		)
		(fp_line
			(start 0.7874 -0.4064)
			(end 0.7874 0.4064)
			(stroke
				(width 0.1524)
				(type default)
			)
			(layer "F.SilkS")
		)
		(fp_line
			(start -0.67945 0.3048)
			(end -0.67945 -0.305054)
			(stroke
				(width 0.1)
				(type default)
			)
			(layer "F.Fab")
		)
		(fp_line
			(start -0.12065 0.3048)
			(end -0.67945 0.3048)
			(stroke
				(width 0.1)
				(type default)
			)
			(layer "F.Fab")
		)
		(fp_line
			(start 0.120396 0.3048)
			(end 0.120396 0.2794)
			(stroke
				(width 0.1)
				(type default)
			)
			(layer "F.Fab")
		)
		(fp_line
			(start 0.67945 0.3048)
			(end 0.120396 0.3048)
			(stroke
				(width 0.1)
				(type default)
			)
			(layer "F.Fab")
		)
		(fp_line
			(start -0.12065 0.2794)
			(end -0.12065 0.3048)
			(stroke
				(width 0.1)
				(type default)
			)
			(layer "F.Fab")
		)
		(fp_line
			(start 0.120396 0.2794)
			(end -0.12065 0.2794)
			(stroke
				(width 0.1)
				(type default)
			)
			(layer "F.Fab")
		)
		(fp_line
			(start -0.12065 -0.2794)
			(end 0.12065 -0.2794)
			(stroke
				(width 0.1)
				(type default)
			)
			(layer "F.Fab")
		)
		(fp_line
			(start 0.12065 -0.2794)
			(end 0.12065 -0.3048)
			(stroke
				(width 0.1)
				(type default)
			)
			(layer "F.Fab")
		)
		(fp_line
			(start 0.12065 -0.3048)
			(end 0.67945 -0.3048)
			(stroke
				(width 0.1)
				(type default)
			)
			(layer "F.Fab")
		)
		(fp_line
			(start 0.67945 -0.3048)
			(end 0.67945 0.3048)
			(stroke
				(width 0.1)
				(type default)
			)
			(layer "F.Fab")
		)
		(fp_line
			(start -0.67945 -0.305054)
			(end -0.12065 -0.305054)
			(stroke
				(width 0.1)
				(type default)
			)
			(layer "F.Fab")
		)
		(fp_line
			(start -0.12065 -0.305054)
			(end -0.12065 -0.2794)
			(stroke
				(width 0.1)
				(type default)
			)
			(layer "F.Fab")
		)
		(pad "1" smd circle
			(at -0.40005 0 270)
			(size 0 0)
			(layers "F.Cu" "F.Mask" "F.Paste")
			(net "P3V3_AUX")
		)
		(pad "2" smd circle
			(at 0.40005 0 270)
			(size 0 0)
			(layers "F.Cu" "F.Mask" "F.Paste")
			(net "USB_HUB2_TI_FULLPWRMGMTZ_MRP_PROG_FUNC3")
		)
	)
)
